# T6G (Grand Teton) — schematic netlist excerpt (pin names and nets, part order shuffled) for the footprints in the layout excerpt that follows; sources: Cadence DE-HDL packaged netlist, KiCad conversion of 04192023_DAF0TMB3IC0_F0TG_MB_C_brd_V02_OCP.brd

C6015  Q_CAP_DIFFBUS  DIFF BUS_0.33UF 6.3V 10% X6S  pkg C0402  page 180 : \1\ = USB3_CPU0_BMC_RX_HUB1_DP ; \2\ = USB3_CPU0_BMC_RX_HUB_C_DP
R6319  Q_RES  10K 1% CHIP  pkg 0402LF  page 178 : A = USB_HUB2_TI_USB_VBUS ; B = GND

(kicad_pcb
	(version 20260206)
	(generator "pcbnew")
	(generator_version "10.0")
	(general
		(thickness 1.6)
		(legacy_teardrops no)
	)
	(paper "A4")
	(title_block
		(title "04192023_DAF0TMB3IC0_F0TG_MB_C_brd_V02_OCP.brd")
		(comment 1 "Grand Teton / footprints 4087-4088 of 8354")
	)
	(layers
		(0 "F.Cu" signal "TOP")
		(4 "In1.Cu" signal "GND")
		(6 "In2.Cu" signal "IN1")
		(8 "In3.Cu" signal "GND1")
		(10 "In4.Cu" signal "IN2")
		(12 "In5.Cu" signal "GND2")
		(14 "In6.Cu" signal "IN3")
		(16 "In7.Cu" signal "GND3")
		(18 "In8.Cu" signal "VCC")
		(20 "In9.Cu" signal "VCC1")
		(22 "In10.Cu" signal "GND4")
		(24 "In11.Cu" signal "IN4")
		(26 "In12.Cu" signal "GND5")
		(28 "In13.Cu" signal "IN5")
		(30 "In14.Cu" signal "GND6")
		(32 "In15.Cu" signal "IN6")
		(34 "In16.Cu" signal "GND7")
		(2 "B.Cu" signal "BOTTOM")
		(9 "F.Adhes" user "F.Adhesive")
		(11 "B.Adhes" user "B.Adhesive")
		(13 "F.Paste" user "Package Geometry/Pastemask Top")
		(15 "B.Paste" user "Package Geometry/Pastemask Bottom")
		(5 "F.SilkS" user "Ref Des/Silkscreen Top")
		(7 "B.SilkS" user "Ref Des/Silkscreen Bottom")
		(1 "F.Mask" user "Board Geometry/Soldermask Top")
		(3 "B.Mask" user "Board Geometry/Soldermask Bottom")
		(17 "Dwgs.User" user "User.Drawings")
		(19 "Cmts.User" user "User.Comments")
		(21 "Eco1.User" user "User.Eco1")
		(23 "Eco2.User" user "User.Eco2")
		(25 "Edge.Cuts" user "Board Geometry/Outline")
		(27 "Margin" user)
		(31 "F.CrtYd" user "Package Geometry/Place Bound Top")
		(29 "B.CrtYd" user "Package Geometry/Place Bound Bottom")
		(35 "F.Fab" user "Ref Des/Assembly Top")
		(33 "B.Fab" user "Ref Des/Assembly Bottom")
	)
	(footprint ""
		(layer "F.Cu")
		(at 104.469946 -54.882034 90)
		(property "Reference" "R6319"
			(at 0 0 90)
			(layer "F.SilkS")
			(hide yes)
			(effects
				(font
					(size 1.27 1.27)
				)
			)
		)
		(property "Value" ""
			(at 0 0 90)
			(layer "F.Fab")
			(effects
				(font
					(size 1.27 1.27)
				)
			)
		)
		(duplicate_pad_numbers_are_jumpers no)
		(fp_line
			(start 0.7874 -0.4064)
			(end 0.7874 0.4064)
			(stroke
				(width 0.1524)
				(type default)
			)
			(layer "F.SilkS")
		)
		(fp_line
			(start -0.7874 -0.4064)
			(end 0.7874 -0.4064)
			(stroke
				(width 0.1524)
				(type default)
			)
			(layer "F.SilkS")
		)
		(fp_line
			(start 0.7874 0.4064)
			(end -0.7874 0.4064)
			(stroke
				(width 0.1524)
				(type default)
			)
			(layer "F.SilkS")
		)
		(fp_line
			(start -0.7874 0.4064)
			(end -0.7874 -0.4064)
			(stroke
				(width 0.1524)
				(type default)
			)
			(layer "F.SilkS")
		)
		(fp_line
			(start -0.12065 -0.305054)
			(end -0.12065 -0.2794)
			(stroke
				(width 0.1)
				(type default)
			)
			(layer "F.Fab")
		)
		(fp_line
			(start -0.67945 -0.305054)
			(end -0.12065 -0.305054)
			(stroke
				(width 0.1)
				(type default)
			)
			(layer "F.Fab")
		)
		(fp_line
			(start 0.67945 -0.3048)
			(end 0.67945 0.3048)
			(stroke
				(width 0.1)
				(type default)
			)
			(layer "F.Fab")
		)
		(fp_line
			(start 0.12065 -0.3048)
			(end 0.67945 -0.3048)
			(stroke
				(width 0.1)
				(type default)
			)
			(layer "F.Fab")
		)
		(fp_line
			(start 0.12065 -0.2794)
			(end 0.12065 -0.3048)
			(stroke
				(width 0.1)
				(type default)
			)
			(layer "F.Fab")
		)
		(fp_line
			(start -0.12065 -0.2794)
			(end 0.12065 -0.2794)
			(stroke
				(width 0.1)
				(type default)
			)
			(layer "F.Fab")
		)
		(fp_line
			(start 0.120396 0.2794)
			(end -0.12065 0.2794)
			(stroke
				(width 0.1)
				(type default)
			)
			(layer "F.Fab")
		)
		(fp_line
			(start -0.12065 0.2794)
			(end -0.12065 0.3048)
			(stroke
				(width 0.1)
				(type default)
			)
			(layer "F.Fab")
		)
		(fp_line
			(start 0.67945 0.3048)
			(end 0.120396 0.3048)
			(stroke
				(width 0.1)
				(type default)
			)
			(layer "F.Fab")
		)
		(fp_line
			(start 0.120396 0.3048)
			(end 0.120396 0.2794)
			(stroke
				(width 0.1)
				(type default)
			)
			(layer "F.Fab")
		)
		(fp_line
			(start -0.12065 0.3048)
			(end -0.67945 0.3048)
			(stroke
				(width 0.1)
				(type default)
			)
			(layer "F.Fab")
		)
		(fp_line
			(start -0.67945 0.3048)
			(end -0.67945 -0.305054)
			(stroke
				(width 0.1)
				(type default)
			)
			(layer "F.Fab")
		)
		(pad "1" smd circle
			(at -0.40005 0 90)
			(size 0 0)
			(layers "F.Cu" "F.Mask" "F.Paste")
			(net "USB_HUB2_TI_USB_VBUS")
		)
		(pad "2" smd circle
			(at 0.40005 0 90)
			(size 0 0)
			(layers "F.Cu" "F.Mask" "F.Paste")
			(net "GND")
		)
	)
	(footprint ""
		(layer "F.Cu")
		(at 141.29512 -31.62681 -90)
		(property "Reference" "C6015"
			(at 0 0 270)
			(layer "F.SilkS")
			(hide yes)
			(effects
				(font
					(size 1.27 1.27)
				)
			)
		)
		(property "Value" ""
			(at 0 0 270)
			(layer "F.Fab")
			(effects
				(font
					(size 1.27 1.27)
				)
			)
		)
		(duplicate_pad_numbers_are_jumpers no)
		(fp_line
			(start -0.40005 -0.4064)
			(end 0.40005 -0.4064)
			(stroke
				(width 0.1524)
				(type default)
			)
			(layer "F.SilkS")
		)
		(fp_line
			(start -0.6858 0.3048)
			(end -0.6858 -0.3048)
			(stroke
				(width 0.1)
				(type default)
			)
			(layer "F.Fab")
		)
		(fp_line
			(start -0.1016 0.3048)
			(end -0.6858 0.3048)
			(stroke
				(width 0.1)
				(type default)
			)
			(layer "F.Fab")
		)
		(fp_line
			(start 0.1016 0.3048)
			(end 0.1016 0.2794)
			(stroke
				(width 0.1)
				(type default)
			)
			(layer "F.Fab")
		)
		(fp_line
			(start 0.6858 0.3048)
			(end 0.1016 0.3048)
			(stroke
				(width 0.1)
				(type default)
			)
			(layer "F.Fab")
		)
		(fp_line
			(start -0.1016 0.2794)
			(end -0.1016 0.3048)
			(stroke
				(width 0.1)
				(type default)
			)
			(layer "F.Fab")
		)
		(fp_line
			(start 0.1016 0.2794)
			(end -0.1016 0.2794)
			(stroke
				(width 0.1)
				(type default)
			)
			(layer "F.Fab")
		)
		(fp_line
			(start -0.1016 -0.2794)
			(end 0.1016 -0.2794)
			(stroke
				(width 0.1)
				(type default)
			)
			(layer "F.Fab")
		)
		(fp_line
			(start 0.1016 -0.2794)
			(end 0.1016 -0.3048)
			(stroke
				(width 0.1)
				(type default)
			)
			(layer "F.Fab")
		)
		(fp_line
			(start -0.6858 -0.3048)
			(end -0.1016 -0.3048)
			(stroke
				(width 0.1)
				(type default)
			)
			(layer "F.Fab")
		)
		(fp_line
			(start -0.1016 -0.3048)
			(end -0.1016 -0.2794)
			(stroke
				(width 0.1)
				(type default)
			)
			(layer "F.Fab")
		)
		(fp_line
			(start 0.1016 -0.3048)
			(end 0.6858 -0.3048)
			(stroke
				(width 0.1)
				(type default)
			)
			(layer "F.Fab")
		)
		(fp_line
			(start 0.6858 -0.3048)
			(end 0.6858 0.3048)
			(stroke
				(width 0.1)
				(type default)
			)
			(layer "F.Fab")
		)
		(pad "1" smd rect
			(at -0.40005 0 90)
			(size 0.4572 0.508)
			(layers "F.Cu" "F.Mask" "F.Paste")
			(net "USB3_CPU0_BMC_RX_HUB1_DP")
		)
		(pad "2" smd rect
			(at 0.40005 0 90)
			(size 0.4572 0.508)
			(layers "F.Cu" "F.Mask" "F.Paste")
			(net "USB3_CPU0_BMC_RX_HUB_C_DP")
		)
	)
)
